FILE_TYPE = MULTI_PHYS_TABLE;
PART 'TPS3700'
{=========================================================================================================================================================================================}
:PACK_TYPE | MATERIAL | PART_NUMBER     = EnvComp | PART_NUMBER  | JEDEC_TYPE     | DESCRIPTION          | CLASS | COMPONENT_TYPE | HEIGHT      | LPID | SPEED_URL | Status |RPL| AML | Bus_Unit | Days;
{=========================================================================================================================================================================================}
'SM'       | 'IC'     | 'H69492-001'(!) = ''      | 'H69492-001' | 'MLFP6_6_5MB'  | 'IC,LIN,TPS3700,REF' | 'IC'  | 'LCC'           | '0.031 IN'  |'3849'| 'http://speed.intel.com:8081/speed/module/pdm/item/pdm_item_detail_direct.asp?item_cde=H69492-001&item_rev=01&url_param=unused' | '' | '' | '' | '' | '' 
'SM'       | 'EMPTY'  | 'H69492-001'(!) = ''      | 'H69492-001' | 'MLFP6_6_5MB'  | 'IC,LIN,TPS3700,REF' | 'IO'  | 'LCC'           | '0.031 IN'  |'3849'| 'http://speed.intel.com:8081/speed/module/pdm/item/pdm_item_detail_direct.asp?item_cde=H69492-001&item_rev=01&url_param=unused' | '' | '' | '' | '' | '' 
END_PART
END.
